(kicad_pcb
	(version 20260206)
	(generator "pcbnew")
	(generator_version "10.0")
	(general
		(thickness 1.6)
		(legacy_teardrops no)
	)
	(paper "A4")
	(title_block
		(title "pdpb — Lightning_PDPB_BRD.brd")
		(comment 1 "Lightning (Wiwynn / Facebook NVMe JBOF) / footprints 558-563 of 1140")
	)
	(layers
		(0 "F.Cu" signal "TOP")
		(4 "In1.Cu" signal "L2GND")
		(6 "In2.Cu" signal "L3")
		(8 "In3.Cu" signal "L4VCC")
		(10 "In4.Cu" signal "L5VCC")
		(12 "In5.Cu" signal "L6")
		(14 "In6.Cu" signal "L7GND")
		(2 "B.Cu" signal "BOTTOM")
		(9 "F.Adhes" user "F.Adhesive")
		(11 "B.Adhes" user "B.Adhesive")
		(13 "F.Paste" user "Package Geometry/Pastemask Top")
		(15 "B.Paste" user "Package Geometry/Pastemask Bottom")
		(5 "F.SilkS" user "Ref Des/Silkscreen Top")
		(7 "B.SilkS" user "Ref Des/Silkscreen Bottom")
		(1 "F.Mask" user "Board Geometry/Soldermask Top")
		(3 "B.Mask" user "Board Geometry/Soldermask Bottom")
		(17 "Dwgs.User" user "User.Drawings")
		(19 "Cmts.User" user "User.Comments")
		(21 "Eco1.User" user "User.Eco1")
		(23 "Eco2.User" user "User.Eco2")
		(25 "Edge.Cuts" user "Board Geometry/Outline")
		(27 "Margin" user)
		(31 "F.CrtYd" user "Package Geometry/Place Bound Top")
		(29 "B.CrtYd" user "Package Geometry/Place Bound Bottom")
		(35 "F.Fab" user "Ref Des/Assembly Top")
		(33 "B.Fab" user "Ref Des/Assembly Bottom")
	)
	(footprint ""
		(layer "F.Cu")
		(at 17.1704 -469.4936 180)
		(property "Reference" "Q80"
			(at 0 0 180)
			(layer "F.SilkS")
			(hide yes)
			(effects
				(font
					(size 1.27 1.27)
				)
			)
		)
		(property "Value" "2N7002A-7-GP"
			(at 0.127 -8.9662 180)
			(unlocked yes)
			(layer "F.Fab")
			(hide yes)
			(effects
				(font
					(size 1.016 1.016)
					(thickness 0.1524)
				)
			)
		)
		(property "Device Type" "SOT23DGS2D4H48"
			(at 0.127 -10.4902 180)
			(unlocked yes)
			(layer "F.Fab")
			(hide yes)
			(effects
				(font
					(size 1.016 1.016)
					(thickness 0.1524)
				)
			)
		)
		(duplicate_pad_numbers_are_jumpers no)
		(fp_line
			(start 1.651 1.778)
			(end 1.651 -1.778)
			(stroke
				(width 0.1524)
				(type default)
			)
			(layer "F.SilkS")
		)
		(fp_line
			(start 1.651 -1.778)
			(end -1.651 -1.778)
			(stroke
				(width 0.1524)
				(type default)
			)
			(layer "F.SilkS")
		)
		(fp_line
			(start -1.651 1.778)
			(end 1.651 1.778)
			(stroke
				(width 0.1524)
				(type default)
			)
			(layer "F.SilkS")
		)
		(fp_line
			(start -1.651 -1.778)
			(end -1.651 1.778)
			(stroke
				(width 0.1524)
				(type default)
			)
			(layer "F.SilkS")
		)
		(fp_poly
			(pts
				(xy -1.778 1.8796) (xy -1.778 -1.8796) (xy 1.778 -1.8796) (xy 1.778 1.8796)
			)
			(stroke
				(width 0)
				(type default)
			)
			(fill no)
			(layer "F.CrtYd")
		)
		(fp_poly
			(pts
				(xy -1.778 1.8796) (xy -1.778 -1.8796) (xy 1.778 -1.8796) (xy 1.778 1.8796)
			)
			(stroke
				(width 0)
				(type default)
			)
			(fill no)
			(layer "F.Fab")
		)
		(pad "D" smd custom
			(at 0 -0.9525 180)
			(size 0.1905 0.1905)
			(layers "F.Cu" "F.Mask" "F.Paste")
			(net "ATTN_LED_DR10_MOS_N")
			(options
				(clearance outline)
				(anchor circle)
			)
			(primitives
				(gr_poly
					(pts
						(arc
							(start -0.1778 0.5715)
							(mid -0.321484 0.511984)
							(end -0.381 0.3683)
						)
						(arc
							(start -0.381 -0.3683)
							(mid -0.321484 -0.511984)
							(end -0.1778 -0.5715)
						)
						(arc
							(start 0.1778 -0.5715)
							(mid 0.321484 -0.511984)
							(end 0.381 -0.3683)
						)
						(arc
							(start 0.381 0.3683)
							(mid 0.321484 0.511984)
							(end 0.1778 0.5715)
						)
					)
					(width 0)
					(fill yes)
				)
			)
		)
		(pad "G" smd custom
			(at -0.98425 0.9525 180)
			(size 0.1905 0.1905)
			(layers "F.Cu" "F.Mask" "F.Paste")
			(net "SSD10_CLK0_OE_MOS_N")
			(options
				(clearance outline)
				(anchor circle)
			)
			(primitives
				(gr_poly
					(pts
						(arc
							(start -0.1778 0.5715)
							(mid -0.321484 0.511984)
							(end -0.381 0.3683)
						)
						(arc
							(start -0.381 -0.3683)
							(mid -0.321484 -0.511984)
							(end -0.1778 -0.5715)
						)
						(arc
							(start 0.1778 -0.5715)
							(mid 0.321484 -0.511984)
							(end 0.381 -0.3683)
						)
						(arc
							(start 0.381 0.3683)
							(mid 0.321484 0.511984)
							(end 0.1778 0.5715)
						)
					)
					(width 0)
					(fill yes)
				)
			)
		)
		(pad "S" smd custom
			(at 0.98425 0.9525 180)
			(size 0.1905 0.1905)
			(layers "F.Cu" "F.Mask" "F.Paste")
			(net "ATTN_LED_DR10_R")
			(options
				(clearance outline)
				(anchor circle)
			)
			(primitives
				(gr_poly
					(pts
						(arc
							(start -0.1778 0.5715)
							(mid -0.321484 0.511984)
							(end -0.381 0.3683)
						)
						(arc
							(start -0.381 -0.3683)
							(mid -0.321484 -0.511984)
							(end -0.1778 -0.5715)
						)
						(arc
							(start 0.1778 -0.5715)
							(mid 0.321484 -0.511984)
							(end 0.381 -0.3683)
						)
						(arc
							(start 0.381 0.3683)
							(mid 0.321484 0.511984)
							(end 0.1778 0.5715)
						)
					)
					(width 0)
					(fill yes)
				)
			)
		)
	)
	(footprint ""
		(layer "F.Cu")
		(at 193.526156 -499.943628 90)
		(property "Reference" "R9776"
			(at 0 0 90)
			(layer "F.SilkS")
			(hide yes)
			(effects
				(font
					(size 1.27 1.27)
				)
			)
		)
		(property "Value" "1KR2J-1-GP"
			(at 0.064008 -3.993896 90)
			(unlocked yes)
			(layer "F.Fab")
			(hide yes)
			(effects
				(font
					(size 1.016 1.016)
					(thickness 0.1524)
				)
			)
		)
		(property "Device Type" "R402H16"
			(at 0.064008 -5.517896 90)
			(unlocked yes)
			(layer "F.Fab")
			(hide yes)
			(effects
				(font
					(size 1.016 1.016)
					(thickness 0.1524)
				)
			)
		)
		(duplicate_pad_numbers_are_jumpers no)
		(fp_line
			(start 0.508 -0.9398)
			(end -0.508 -0.9398)
			(stroke
				(width 0.1524)
				(type default)
			)
			(layer "F.SilkS")
		)
		(fp_line
			(start -0.508 -0.9398)
			(end -0.508 0.9398)
			(stroke
				(width 0.1524)
				(type default)
			)
			(layer "F.SilkS")
		)
		(fp_rect
			(start -0.508 0.9398)
			(end 0.508 -0.9398)
			(stroke
				(width 0)
				(type default)
			)
			(fill no)
			(layer "F.CrtYd")
		)
		(fp_rect
			(start -0.508 0.9398)
			(end 0.508 -0.9398)
			(stroke
				(width 0)
				(type default)
			)
			(fill no)
			(layer "F.Fab")
		)
		(pad "1" smd custom
			(at 0 -0.4445 90)
			(size 0.1397 0.1397)
			(layers "F.Cu" "F.Mask" "F.Paste")
			(net "SSD0_PWREN")
			(options
				(clearance outline)
				(anchor circle)
			)
			(primitives
				(gr_poly
					(pts
						(arc
							(start -0.1778 -0.2794)
							(mid -0.249642 -0.249642)
							(end -0.2794 -0.1778)
						)
						(arc
							(start -0.2794 0.1778)
							(mid -0.249642 0.249642)
							(end -0.1778 0.2794)
						)
						(arc
							(start 0.1778 0.2794)
							(mid 0.249642 0.249642)
							(end 0.2794 0.1778)
						)
						(arc
							(start 0.2794 -0.1778)
							(mid 0.249642 -0.249642)
							(end 0.1778 -0.2794)
						)
					)
					(width 0)
					(fill yes)
				)
			)
		)
		(pad "2" smd custom
			(at 0 0.4445 90)
			(size 0.1397 0.1397)
			(layers "F.Cu" "F.Mask" "F.Paste")
			(net "SSD0_PWREN_R")
			(options
				(clearance outline)
				(anchor circle)
			)
			(primitives
				(gr_poly
					(pts
						(arc
							(start -0.1778 -0.2794)
							(mid -0.249642 -0.249642)
							(end -0.2794 -0.1778)
						)
						(arc
							(start -0.2794 0.1778)
							(mid -0.249642 0.249642)
							(end -0.1778 0.2794)
						)
						(arc
							(start 0.1778 0.2794)
							(mid 0.249642 0.249642)
							(end 0.2794 0.1778)
						)
						(arc
							(start 0.2794 -0.1778)
							(mid 0.249642 -0.249642)
							(end 0.1778 -0.2794)
						)
					)
					(width 0)
					(fill yes)
				)
			)
		)
	)
	(footprint ""
		(layer "F.Cu")
		(at 35.0266 -194.3608 180)
		(property "Reference" "PC1215"
			(at 0 0 180)
			(layer "F.SilkS")
			(hide yes)
			(effects
				(font
					(size 1.27 1.27)
				)
			)
		)
		(property "Value" "SC22U25V6KX-GP-U"
			(at -2.860802 -5.279644 180)
			(unlocked yes)
			(layer "F.Fab")
			(hide yes)
			(effects
				(font
					(size 1.016 1.016)
					(thickness 0.1524)
				)
			)
		)
		(property "Device Type" "C1206-TO0D3H75"
			(at -2.860802 -6.803644 180)
			(unlocked yes)
			(layer "F.Fab")
			(hide yes)
			(effects
				(font
					(size 1.016 1.016)
					(thickness 0.1524)
				)
			)
		)
		(duplicate_pad_numbers_are_jumpers no)
		(fp_line
			(start 1.3081 2.3749)
			(end -1.3081 2.3749)
			(stroke
				(width 0.1524)
				(type default)
			)
			(layer "F.SilkS")
		)
		(fp_line
			(start 1.3081 -2.3749)
			(end 1.3081 2.3749)
			(stroke
				(width 0.1524)
				(type default)
			)
			(layer "F.SilkS")
		)
		(fp_line
			(start -1.3081 2.3749)
			(end -1.3081 -2.3749)
			(stroke
				(width 0.1524)
				(type default)
			)
			(layer "F.SilkS")
		)
		(fp_line
			(start -1.3081 -2.3749)
			(end 1.3081 -2.3749)
			(stroke
				(width 0.1524)
				(type default)
			)
			(layer "F.SilkS")
		)
		(fp_rect
			(start -0.8001 1.6002)
			(end 0.8001 -1.6002)
			(stroke
				(width 0)
				(type default)
			)
			(fill no)
			(layer "F.CrtYd")
		)
		(fp_poly
			(pts
				(xy -1.5621 2.4511) (xy -1.5621 1.6002) (xy 0.8001 1.6002) (xy 0.8001 -1.6002) (xy -0.8001 -1.6002)
				(xy -0.8001 1.5875) (xy -1.5621 1.5875) (xy -1.5621 -2.4511) (xy 1.5621 -2.4511) (xy 1.5621 2.4511)
			)
			(stroke
				(width 0)
				(type default)
			)
			(fill no)
			(layer "F.CrtYd")
		)
		(fp_rect
			(start -1.5621 2.4511)
			(end 1.5621 -2.4511)
			(stroke
				(width 0)
				(type default)
			)
			(fill no)
			(layer "F.Fab")
		)
		(pad "1" smd rect
			(at 0 -1.392936 180)
			(size 2.1082 1.4478)
			(layers "F.Cu" "F.Mask" "F.Paste")
			(net "P12V_SSD8")
		)
		(pad "2" smd rect
			(at 0 1.392936 180)
			(size 2.1082 1.4478)
			(layers "F.Cu" "F.Mask" "F.Paste")
			(net "GND")
		)
	)
	(footprint ""
		(layer "F.Cu")
		(at 34.13125 -41.26865 -90)
		(property "Reference" "SR1139"
			(at 0 0 270)
			(layer "F.SilkS")
			(hide yes)
			(effects
				(font
					(size 1.27 1.27)
				)
			)
		)
		(property "Value" "4K7R2F-GP"
			(at 0.064008 -3.993896 270)
			(unlocked yes)
			(layer "F.Fab")
			(hide yes)
			(effects
				(font
					(size 1.016 1.016)
					(thickness 0.1524)
				)
			)
		)
		(property "Device Type" "R402H16"
			(at 0.064008 -5.517896 270)
			(unlocked yes)
			(layer "F.Fab")
			(hide yes)
			(effects
				(font
					(size 1.016 1.016)
					(thickness 0.1524)
				)
			)
		)
		(duplicate_pad_numbers_are_jumpers no)
		(fp_line
			(start -0.508 -0.9398)
			(end -0.508 0.9398)
			(stroke
				(width 0.1524)
				(type default)
			)
			(layer "F.SilkS")
		)
		(fp_line
			(start 0.508 -0.9398)
			(end -0.508 -0.9398)
			(stroke
				(width 0.1524)
				(type default)
			)
			(layer "F.SilkS")
		)
		(fp_rect
			(start -0.508 0.9398)
			(end 0.508 -0.9398)
			(stroke
				(width 0)
				(type default)
			)
			(fill no)
			(layer "F.CrtYd")
		)
		(fp_rect
			(start -0.508 0.9398)
			(end 0.508 -0.9398)
			(stroke
				(width 0)
				(type default)
			)
			(fill no)
			(layer "F.Fab")
		)
		(pad "1" smd custom
			(at 0 -0.4445 270)
			(size 0.1397 0.1397)
			(layers "F.Cu" "F.Mask" "F.Paste")
			(net "P3V3")
			(options
				(clearance outline)
				(anchor circle)
			)
			(primitives
				(gr_poly
					(pts
						(arc
							(start -0.1778 -0.2794)
							(mid -0.249642 -0.249642)
							(end -0.2794 -0.1778)
						)
						(arc
							(start -0.2794 0.1778)
							(mid -0.249642 0.249642)
							(end -0.1778 0.2794)
						)
						(arc
							(start 0.1778 0.2794)
							(mid 0.249642 0.249642)
							(end 0.2794 0.1778)
						)
						(arc
							(start 0.2794 -0.1778)
							(mid 0.249642 -0.249642)
							(end 0.1778 -0.2794)
						)
					)
					(width 0)
					(fill yes)
				)
			)
		)
		(pad "2" smd custom
			(at 0 0.4445 270)
			(size 0.1397 0.1397)
			(layers "F.Cu" "F.Mask" "F.Paste")
			(net "SSD9_CLK0_OE_MOS_N")
			(options
				(clearance outline)
				(anchor circle)
			)
			(primitives
				(gr_poly
					(pts
						(arc
							(start -0.1778 -0.2794)
							(mid -0.249642 -0.249642)
							(end -0.2794 -0.1778)
						)
						(arc
							(start -0.2794 0.1778)
							(mid -0.249642 0.249642)
							(end -0.1778 0.2794)
						)
						(arc
							(start 0.1778 0.2794)
							(mid 0.249642 0.249642)
							(end 0.2794 0.1778)
						)
						(arc
							(start 0.2794 -0.1778)
							(mid 0.249642 -0.249642)
							(end 0.1778 -0.2794)
						)
					)
					(width 0)
					(fill yes)
				)
			)
		)
	)
	(footprint ""
		(layer "F.Cu")
		(at 70.358 -447.929 180)
		(property "Reference" "U50"
			(at 0 0 180)
			(layer "F.SilkS")
			(hide yes)
			(effects
				(font
					(size 1.27 1.27)
				)
			)
		)
		(property "Value" "24LC64T-I-GP"
			(at 0 -12.1412 180)
			(unlocked yes)
			(layer "F.Fab")
			(hide yes)
			(effects
				(font
					(size 1.016 1.016)
					(thickness 0.1524)
				)
			)
		)
		(property "Device Type" "SSOIC8-1H44"
			(at 0 -13.6652 180)
			(unlocked yes)
			(layer "F.Fab")
			(hide yes)
			(effects
				(font
					(size 1.016 1.016)
					(thickness 0.1524)
				)
			)
		)
		(duplicate_pad_numbers_are_jumpers no)
		(fp_line
			(start 1.397 1.778)
			(end -1.778 1.778)
			(stroke
				(width 0.2032)
				(type default)
			)
			(layer "F.SilkS")
		)
		(fp_line
			(start 1.397 -1.778)
			(end 1.397 1.778)
			(stroke
				(width 0.2032)
				(type default)
			)
			(layer "F.SilkS")
		)
		(fp_line
			(start -1.143 0)
			(end -1.778 0.635)
			(stroke
				(width 0.2032)
				(type default)
			)
			(layer "F.SilkS")
		)
		(fp_line
			(start -1.143 0)
			(end -1.778 -0.635)
			(stroke
				(width 0.2032)
				(type default)
			)
			(layer "F.SilkS")
		)
		(fp_line
			(start -1.778 1.778)
			(end -1.778 3.81)
			(stroke
				(width 0.508)
				(type default)
			)
			(layer "F.SilkS")
		)
		(fp_line
			(start -1.778 -1.778)
			(end 1.397 -1.778)
			(stroke
				(width 0.2032)
				(type default)
			)
			(layer "F.SilkS")
		)
		(fp_line
			(start -1.778 -1.778)
			(end -1.778 2.667)
			(stroke
				(width 0.2032)
				(type default)
			)
			(layer "F.SilkS")
		)
		(fp_poly
			(pts
				(xy -2.032 3.81) (xy 2.032 3.81) (xy 2.032 -3.81) (xy -2.032 -3.81)
			)
			(stroke
				(width 0)
				(type default)
			)
			(fill no)
			(layer "F.CrtYd")
		)
		(fp_poly
			(pts
				(xy -2.032 -3.81) (xy 2.032 -3.81) (xy 2.032 3.81) (xy -2.032 3.81)
			)
			(stroke
				(width 0)
				(type default)
			)
			(fill no)
			(layer "F.Fab")
		)
		(pad "1" smd rect
			(at -0.97536 2.8194 180)
			(size 0.3556 1.524)
			(layers "F.Cu" "F.Mask" "F.Paste")
			(net "EEPROM_A0")
		)
		(pad "2" smd rect
			(at -0.32512 2.8194 180)
			(size 0.3556 1.524)
			(layers "F.Cu" "F.Mask" "F.Paste")
			(net "EEPROM_A1")
		)
		(pad "3" smd rect
			(at 0.32512 2.8194 180)
			(size 0.3556 1.524)
			(layers "F.Cu" "F.Mask" "F.Paste")
			(net "EEPROM_A2")
		)
		(pad "4" smd rect
			(at 0.97536 2.8194 180)
			(size 0.3556 1.524)
			(layers "F.Cu" "F.Mask" "F.Paste")
			(net "GND")
		)
		(pad "5" smd rect
			(at 0.97536 -2.8194 180)
			(size 0.3556 1.524)
			(layers "F.Cu" "F.Mask" "F.Paste")
			(net "EEPROM_SDA")
		)
		(pad "6" smd rect
			(at 0.32512 -2.8194 180)
			(size 0.3556 1.524)
			(layers "F.Cu" "F.Mask" "F.Paste")
			(net "EEPROM_SCL")
		)
		(pad "7" smd rect
			(at -0.32512 -2.8194 180)
			(size 0.3556 1.524)
			(layers "F.Cu" "F.Mask" "F.Paste")
			(net "EEPROM_WP")
		)
		(pad "8" smd rect
			(at -0.97536 -2.8194 180)
			(size 0.3556 1.524)
			(layers "F.Cu" "F.Mask" "F.Paste")
			(net "P3V3")
		)
	)
	(footprint ""
		(layer "F.Cu")
		(at 219.329 -449.58 90)
		(property "Reference" "SR1121"
			(at 0 0 90)
			(layer "F.SilkS")
			(hide yes)
			(effects
				(font
					(size 1.27 1.27)
				)
			)
		)
		(property "Value" "4K7R2F-GP"
			(at 0.064008 -3.993896 90)
			(unlocked yes)
			(layer "F.Fab")
			(hide yes)
			(effects
				(font
					(size 1.016 1.016)
					(thickness 0.1524)
				)
			)
		)
		(property "Device Type" "R402H16"
			(at 0.064008 -5.517896 90)
			(unlocked yes)
			(layer "F.Fab")
			(hide yes)
			(effects
				(font
					(size 1.016 1.016)
					(thickness 0.1524)
				)
			)
		)
		(duplicate_pad_numbers_are_jumpers no)
		(fp_line
			(start 0.508 -0.9398)
			(end -0.508 -0.9398)
			(stroke
				(width 0.1524)
				(type default)
			)
			(layer "F.SilkS")
		)
		(fp_line
			(start -0.508 -0.9398)
			(end -0.508 0.9398)
			(stroke
				(width 0.1524)
				(type default)
			)
			(layer "F.SilkS")
		)
		(fp_rect
			(start -0.508 0.9398)
			(end 0.508 -0.9398)
			(stroke
				(width 0)
				(type default)
			)
			(fill no)
			(layer "F.CrtYd")
		)
		(fp_rect
			(start -0.508 0.9398)
			(end 0.508 -0.9398)
			(stroke
				(width 0)
				(type default)
			)
			(fill no)
			(layer "F.Fab")
		)
		(pad "1" smd custom
			(at 0 -0.4445 90)
			(size 0.1397 0.1397)
			(layers "F.Cu" "F.Mask" "F.Paste")
			(net "P3V3")
			(options
				(clearance outline)
				(anchor circle)
			)
			(primitives
				(gr_poly
					(pts
						(arc
							(start -0.1778 -0.2794)
							(mid -0.249642 -0.249642)
							(end -0.2794 -0.1778)
						)
						(arc
							(start -0.2794 0.1778)
							(mid -0.249642 0.249642)
							(end -0.1778 0.2794)
						)
						(arc
							(start 0.1778 0.2794)
							(mid 0.249642 0.249642)
							(end 0.2794 0.1778)
						)
						(arc
							(start 0.2794 -0.1778)
							(mid 0.249642 -0.249642)
							(end 0.1778 -0.2794)
						)
					)
					(width 0)
					(fill yes)
				)
			)
		)
		(pad "2" smd custom
			(at 0 0.4445 90)
			(size 0.1397 0.1397)
			(layers "F.Cu" "F.Mask" "F.Paste")
			(net "SSD0_CLK0_OE_MOS_N")
			(options
				(clearance outline)
				(anchor circle)
			)
			(primitives
				(gr_poly
					(pts
						(arc
							(start -0.1778 -0.2794)
							(mid -0.249642 -0.249642)
							(end -0.2794 -0.1778)
						)
						(arc
							(start -0.2794 0.1778)
							(mid -0.249642 0.249642)
							(end -0.1778 0.2794)
						)
						(arc
							(start 0.1778 0.2794)
							(mid 0.249642 0.249642)
							(end 0.2794 0.1778)
						)
						(arc
							(start 0.2794 -0.1778)
							(mid 0.249642 -0.249642)
							(end 0.1778 -0.2794)
						)
					)
					(width 0)
					(fill yes)
				)
			)
		)
	)
)
